FILE_TYPE = MACRO_DRAWING;
SET COLOR_WIRE YELLOW;
SET COLOR_PROP MONO;
SET COLOR_DOT WHITE;
SET COLOR_ARC YELLOW;
SET COLOR_BODY GREEN;
SET COLOR_NOTE MONO;
SET PROP_DISPLAY VALUE;
SET PAGE_NUMBER P16;
FORCEADD INTEL_CORP_BPAGE..1
(0 0);
FORCEPROP 1 LAST CDS_CON_LAST_MODIFIED Fri Jun 16 17:48:02 2017
J 0
(-1425 325);
PAINT ORANGE (-1425 325);
DISPLAY INVISIBLE (-1425 325);
FORCEPROP 1 LAST CUSTOM_TXT_CDS <CURRENT_DESIGN_SHEET> OF <TOTAL_DESIGN_SHEETS>
J 0
(-500 25);
PAINT ORANGE (-500 25);
FORCEPROP 1 LAST CUSTOM_TXT_CDS <CON_LAST_MODIFIED>
J 0
(-4000 100);
PAINT ORANGE (-4000 100);
FORCEPROP 2 LAST CUSTOM_TXT_CDS <XR_PAGE_TITLE>
J 0
(-7890 5250);
DISPLAY 0.638298 (-7890 5250);
PAINT PINK (-7890 5250);
DISPLAY INVISIBLE (-7890 5250);
FORCEPROP 1 LAST SCH_TITLE POWER/RESET TIMING G3>S5
J 0
(-7950 50);
DISPLAY 1.212766 (-7950 50);
PAINT ORANGE (-7950 50);
FORCEPROP 2 LAST CDS_LIB mstr_symbols
J 0
(0 0);
PAINT MONO (0 0);
DISPLAY INVISIBLE (0 0);
FORCEPROP 2 LAST PAGE_BORDER TRUE
J 0
(-7890 5250);
DISPLAY 0.638298 (-7890 5250);
PAINT PINK (-7890 5250);
DISPLAY INVISIBLE (-7890 5250);
FORCEPROP 1 LAST COMMENT_BODY TRUE
J 0
(12 12);
DISPLAY 0.468085 (12 12);
PAINT GREEN (12 12);
DISPLAY INVISIBLE (12 12);
FORCEPROP 2 LAST CDS_XR_PAGE_TITLE CR-16 : @BASEBOARD_FAB2_LIB.BASEBOARD_FAB2(SCH_1):PAGE16
J 0
(-7890 5250);
DISPLAY 0.638298 (-7890 5250);
PAINT PINK (-7890 5250);
DISPLAY INVISIBLE (-7890 5250);
QUIT
